# BASEBOARD_FAB2 (Tioga Pass) — schematic netlist excerpt (pin names and nets, part order shuffled) for the footprints in the layout excerpt that follows; sources: Cadence DE-HDL packaged netlist, KiCad conversion of Wiwynn_Tioga_Pass_MB.brd

U9P2  TPS3700  IC  pkg SM  page 200
  OUTB  = FM_HSC_TIMER_EXP_N
  VDD  = P3V3_STBY
  INBN  = A_HSC_TIMER_R
  INAP  = A_HSC_INAP
  GND  = GND
  OUTA  = PWRGD_DSW_PWROK

R6W35  RES  100.0K 1% CHIP  pkg 0402  page 247 : A = P3V3_STBY ; B = FM_CPU_CATERR_MSMI_LVT3_N
R2T59  RES  0.0 5% EMPTY  pkg 0402  page 93 : A = H_CPU0_PROCHOT_G_N ; B = H_CPU0_PROCHOT_G_PCH_N

(kicad_pcb
	(version 20260206)
	(generator "pcbnew")
	(generator_version "10.0")
	(general
		(thickness 1.6)
		(legacy_teardrops no)
	)
	(paper "A4")
	(title_block
		(title "Wiwynn_Tioga_Pass_MB.brd")
		(comment 1 "Tioga Pass / footprints 2801-2803 of 4770")
	)
	(layers
		(0 "F.Cu" signal "TOP")
		(4 "In1.Cu" signal "L2GND")
		(6 "In2.Cu" signal "L3")
		(8 "In3.Cu" signal "L4GND")
		(10 "In4.Cu" signal "L5")
		(12 "In5.Cu" signal "L6GND")
		(14 "In6.Cu" signal "L7VCC")
		(16 "In7.Cu" signal "L8VCC")
		(18 "In8.Cu" signal "L9GND")
		(20 "In9.Cu" signal "L10")
		(22 "In10.Cu" signal "L11GND")
		(24 "In11.Cu" signal "L12")
		(26 "In12.Cu" signal "L13GND")
		(2 "B.Cu" signal "BOTTOM")
		(9 "F.Adhes" user "F.Adhesive")
		(11 "B.Adhes" user "B.Adhesive")
		(13 "F.Paste" user "Package Geometry/Pastemask Top")
		(15 "B.Paste" user "Package Geometry/Pastemask Bottom")
		(5 "F.SilkS" user "Ref Des/Silkscreen Top")
		(7 "B.SilkS" user "Ref Des/Silkscreen Bottom")
		(1 "F.Mask" user "Board Geometry/Soldermask Top")
		(3 "B.Mask" user "Board Geometry/Soldermask Bottom")
		(17 "Dwgs.User" user "User.Drawings")
		(19 "Cmts.User" user "User.Comments")
		(21 "Eco1.User" user "User.Eco1")
		(23 "Eco2.User" user "User.Eco2")
		(25 "Edge.Cuts" user "Board Geometry/Outline")
		(27 "Margin" user)
		(31 "F.CrtYd" user "Package Geometry/Place Bound Top")
		(29 "B.CrtYd" user "Package Geometry/Place Bound Bottom")
		(35 "F.Fab" user "Ref Des/Assembly Top")
		(33 "B.Fab" user "Ref Des/Assembly Bottom")
	)
	(footprint ""
		(layer "B.Cu")
		(at 374.381268 -48.328326 90)
		(property "Reference" "R2T59"
			(at 0 0 90)
			(layer "B.SilkS")
			(hide yes)
			(effects
				(font
					(size 1.27 1.27)
				)
				(justify mirror)
			)
		)
		(property "Value" ""
			(at 0 0 90)
			(layer "B.Fab")
			(effects
				(font
					(size 1.27 1.27)
				)
				(justify mirror)
			)
		)
		(duplicate_pad_numbers_are_jumpers no)
		(fp_poly
			(pts
				(xy 0.2794 -0.1016) (xy -0.2794 -0.1016) (xy -0.2794 0.9906) (xy 0.2794 0.9906)
			)
			(stroke
				(width 0)
				(type default)
			)
			(fill no)
			(layer "B.CrtYd")
		)
		(fp_line
			(start 0.2794 -0.1016)
			(end 0.2794 0.9906)
			(stroke
				(width 0.1)
				(type default)
			)
			(layer "B.Fab")
		)
		(fp_line
			(start -0.2794 -0.1016)
			(end 0.2794 -0.1016)
			(stroke
				(width 0.1)
				(type default)
			)
			(layer "B.Fab")
		)
		(fp_line
			(start 0.2794 0.9906)
			(end -0.2794 0.9906)
			(stroke
				(width 0.1)
				(type default)
			)
			(layer "B.Fab")
		)
		(fp_line
			(start -0.2794 0.9906)
			(end -0.2794 -0.1016)
			(stroke
				(width 0.1)
				(type default)
			)
			(layer "B.Fab")
		)
		(pad "1" smd rect
			(at 0 0 270)
			(size 0.508 0.508)
			(layers "B.Cu" "B.Mask" "B.Paste")
			(net "H_CPU0_PROCHOT_G_N")
		)
		(pad "2" smd rect
			(at 0 0.889 270)
			(size 0.508 0.508)
			(layers "B.Cu" "B.Mask" "B.Paste")
			(net "H_CPU0_PROCHOT_G_PCH_N")
		)
		(zone
			(layer "B.Cu")
			(hatch none 0.5)
			(connect_pads
				(clearance 0)
			)
			(min_thickness 0.25)
			(keepout
				(tracks allowed)
				(vias not_allowed)
				(pads allowed)
				(copperpour not_allowed)
				(footprints allowed)
			)
			(placement
				(enabled no)
				(sheetname "")
			)
			(fill
				(thermal_gap 0.5)
				(thermal_bridge_width 0.5)
				(island_removal_mode 0)
			)
			(polygon
				(pts
					(xy 374.635268 -48.582326) (xy 374.635268 -48.074326) (xy 375.016268 -48.074326) (xy 375.016268 -48.582326)
				)
			)
		)
		(zone
			(layer "B.Cu")
			(hatch none 0.5)
			(connect_pads
				(clearance 0)
			)
			(min_thickness 0.25)
			(keepout
				(tracks not_allowed)
				(vias allowed)
				(pads allowed)
				(copperpour not_allowed)
				(footprints allowed)
			)
			(placement
				(enabled no)
				(sheetname "")
			)
			(fill
				(thermal_gap 0.5)
				(thermal_bridge_width 0.5)
				(island_removal_mode 0)
			)
			(polygon
				(pts
					(xy 375.016268 -48.582326) (xy 375.016268 -48.074326) (xy 374.635268 -48.074326) (xy 374.635268 -48.582326)
				)
			)
		)
	)
	(footprint ""
		(layer "B.Cu")
		(at 469.646 -134.7978 90)
		(property "Reference" "R6W35"
			(at 0.8382 -0.67818 90)
			(unlocked yes)
			(layer "B.SilkS")
			(effects
				(font
					(size 0.4064 0.254)
					(thickness 0.1524)
				)
				(justify left mirror)
			)
		)
		(property "Value" ""
			(at 0 0 90)
			(layer "B.Fab")
			(effects
				(font
					(size 1.27 1.27)
				)
				(justify mirror)
			)
		)
		(duplicate_pad_numbers_are_jumpers no)
		(fp_poly
			(pts
				(xy 0.2794 -0.1016) (xy -0.2794 -0.1016) (xy -0.2794 0.9906) (xy 0.2794 0.9906)
			)
			(stroke
				(width 0)
				(type default)
			)
			(fill no)
			(layer "B.CrtYd")
		)
		(fp_line
			(start 0.2794 -0.1016)
			(end 0.2794 0.9906)
			(stroke
				(width 0.1)
				(type default)
			)
			(layer "B.Fab")
		)
		(fp_line
			(start -0.2794 -0.1016)
			(end 0.2794 -0.1016)
			(stroke
				(width 0.1)
				(type default)
			)
			(layer "B.Fab")
		)
		(fp_line
			(start 0.2794 0.9906)
			(end -0.2794 0.9906)
			(stroke
				(width 0.1)
				(type default)
			)
			(layer "B.Fab")
		)
		(fp_line
			(start -0.2794 0.9906)
			(end -0.2794 -0.1016)
			(stroke
				(width 0.1)
				(type default)
			)
			(layer "B.Fab")
		)
		(pad "1" smd rect
			(at 0 0 270)
			(size 0.508 0.508)
			(layers "B.Cu" "B.Mask" "B.Paste")
			(net "P3V3_STBY")
		)
		(pad "2" smd rect
			(at 0 0.889 270)
			(size 0.508 0.508)
			(layers "B.Cu" "B.Mask" "B.Paste")
			(net "FM_CPU_CATERR_MSMI_LVT3_N")
		)
		(zone
			(layer "B.Cu")
			(hatch none 0.5)
			(connect_pads
				(clearance 0)
			)
			(min_thickness 0.25)
			(keepout
				(tracks allowed)
				(vias not_allowed)
				(pads allowed)
				(copperpour not_allowed)
				(footprints allowed)
			)
			(placement
				(enabled no)
				(sheetname "")
			)
			(fill
				(thermal_gap 0.5)
				(thermal_bridge_width 0.5)
				(island_removal_mode 0)
			)
			(polygon
				(pts
					(xy 469.9 -135.0518) (xy 469.9 -134.5438) (xy 470.281 -134.5438) (xy 470.281 -135.0518)
				)
			)
		)
		(zone
			(layer "B.Cu")
			(hatch none 0.5)
			(connect_pads
				(clearance 0)
			)
			(min_thickness 0.25)
			(keepout
				(tracks not_allowed)
				(vias allowed)
				(pads allowed)
				(copperpour not_allowed)
				(footprints allowed)
			)
			(placement
				(enabled no)
				(sheetname "")
			)
			(fill
				(thermal_gap 0.5)
				(thermal_bridge_width 0.5)
				(island_removal_mode 0)
			)
			(polygon
				(pts
					(xy 470.281 -135.0518) (xy 470.281 -134.5438) (xy 469.9 -134.5438) (xy 469.9 -135.0518)
				)
			)
		)
	)
	(footprint ""
		(layer "B.Cu")
		(at 26.0096 -79.502 -90)
		(property "Reference" "U9P2"
			(at -1.3716 -1.44653 270)
			(unlocked yes)
			(layer "B.SilkS")
			(effects
				(font
					(size 0.7874 0.5842)
					(thickness 0.1524)
				)
				(justify mirror)
			)
		)
		(property "Value" ""
			(at 0 0 90)
			(layer "B.Fab")
			(effects
				(font
					(size 1.27 1.27)
				)
				(justify mirror)
			)
		)
		(duplicate_pad_numbers_are_jumpers no)
		(fp_circle
			(center 0.8255 0.199898)
			(end 0.8255 0.072644)
			(stroke
				(width 0.254)
				(type default)
			)
			(fill no)
			(layer "B.SilkS")
		)
		(fp_rect
			(start 0.216154 1.27508)
			(end -1.333754 -0.275082)
			(stroke
				(width 0)
				(type default)
			)
			(fill no)
			(layer "B.CrtYd")
		)
		(fp_line
			(start -1.333754 1.27508)
			(end 0.216154 1.27508)
			(stroke
				(width 0.1)
				(type default)
			)
			(layer "B.Fab")
		)
		(fp_line
			(start 0.216154 1.27508)
			(end 0.216154 -0.275082)
			(stroke
				(width 0.1)
				(type default)
			)
			(layer "B.Fab")
		)
		(fp_line
			(start -1.333754 -0.275082)
			(end -1.333754 1.27508)
			(stroke
				(width 0.1)
				(type default)
			)
			(layer "B.Fab")
		)
		(fp_line
			(start 0.216154 -0.275082)
			(end -1.333754 -0.275082)
			(stroke
				(width 0.1)
				(type default)
			)
			(layer "B.Fab")
		)
		(fp_circle
			(center 1.0795 -0.054102)
			(end 1.0795 -0.181356)
			(stroke
				(width 0.254)
				(type default)
			)
			(fill no)
			(layer "B.Fab")
		)
		(pad "1" smd rect
			(at 0 0 90)
			(size 0.9398 0.3048)
			(layers "B.Cu" "B.Mask" "B.Paste")
			(net "FM_HSC_TIMER_EXP_N")
		)
		(pad "2" smd rect
			(at 0.0254 0.500126 90)
			(size 0.889 0.3048)
			(layers "B.Cu" "B.Mask" "B.Paste")
			(net "P3V3_STBY")
		)
		(pad "3" smd rect
			(at 0.0254 0.999998 90)
			(size 0.889 0.3048)
			(layers "B.Cu" "B.Mask" "B.Paste")
			(net "A_HSC_TIMER_R")
		)
		(pad "4" smd rect
			(at -1.143 0.999998 90)
			(size 0.889 0.3048)
			(layers "B.Cu" "B.Mask" "B.Paste")
			(net "A_HSC_INAP")
		)
		(pad "5" smd rect
			(at -1.143 0.500126 90)
			(size 0.889 0.3048)
			(layers "B.Cu" "B.Mask" "B.Paste")
			(net "GND")
		)
		(pad "6" smd rect
			(at -1.143 0 90)
			(size 0.889 0.3048)
			(layers "B.Cu" "B.Mask" "B.Paste")
			(net "PWRGD_DSW_PWROK")
		)
	)
)
